# T6G (Grand Teton) — schematic netlist excerpt (pin names and nets, part order shuffled) for the footprints in the layout excerpt that follows; sources: Cadence DE-HDL packaged netlist, KiCad conversion of 04192023_DAF0TMB3IC0_F0TG_MB_C_brd_V02_OCP.brd

PC2211  Q_CAP  1UF 25V 10% X6S  pkg C0402  page 146 : A = GND ; B = P12V_E1S_REG_0
PC1850  Q_CAP  22UF 16V 20% X6S  pkg C0805  page 189 : A = SW_P5V_AUX_FLT ; B = GND
R449  Q_RES  4.7K 5% EMPTY  pkg 0402LF  page 28 : A = CPU0_SLP_S3_N ; B = PVDD18_S5_P0

(kicad_pcb
	(version 20260206)
	(generator "pcbnew")
	(generator_version "10.0")
	(general
		(thickness 1.6)
		(legacy_teardrops no)
	)
	(paper "A4")
	(title_block
		(title "04192023_DAF0TMB3IC0_F0TG_MB_C_brd_V02_OCP.brd")
		(comment 1 "Grand Teton / footprints 4175-4177 of 8354")
	)
	(layers
		(0 "F.Cu" signal "TOP")
		(4 "In1.Cu" signal "GND")
		(6 "In2.Cu" signal "IN1")
		(8 "In3.Cu" signal "GND1")
		(10 "In4.Cu" signal "IN2")
		(12 "In5.Cu" signal "GND2")
		(14 "In6.Cu" signal "IN3")
		(16 "In7.Cu" signal "GND3")
		(18 "In8.Cu" signal "VCC")
		(20 "In9.Cu" signal "VCC1")
		(22 "In10.Cu" signal "GND4")
		(24 "In11.Cu" signal "IN4")
		(26 "In12.Cu" signal "GND5")
		(28 "In13.Cu" signal "IN5")
		(30 "In14.Cu" signal "GND6")
		(32 "In15.Cu" signal "IN6")
		(34 "In16.Cu" signal "GND7")
		(2 "B.Cu" signal "BOTTOM")
		(9 "F.Adhes" user "F.Adhesive")
		(11 "B.Adhes" user "B.Adhesive")
		(13 "F.Paste" user "Package Geometry/Pastemask Top")
		(15 "B.Paste" user "Package Geometry/Pastemask Bottom")
		(5 "F.SilkS" user "Ref Des/Silkscreen Top")
		(7 "B.SilkS" user "Ref Des/Silkscreen Bottom")
		(1 "F.Mask" user "Board Geometry/Soldermask Top")
		(3 "B.Mask" user "Board Geometry/Soldermask Bottom")
		(17 "Dwgs.User" user "User.Drawings")
		(19 "Cmts.User" user "User.Comments")
		(21 "Eco1.User" user "User.Eco1")
		(23 "Eco2.User" user "User.Eco2")
		(25 "Edge.Cuts" user "Board Geometry/Outline")
		(27 "Margin" user)
		(31 "F.CrtYd" user "Package Geometry/Place Bound Top")
		(29 "B.CrtYd" user "Package Geometry/Place Bound Bottom")
		(35 "F.Fab" user "Ref Des/Assembly Top")
		(33 "B.Fab" user "Ref Des/Assembly Bottom")
	)
	(footprint ""
		(layer "F.Cu")
		(at 251.35967 -45.987462 -90)
		(property "Reference" "PC2211"
			(at 0 0 270)
			(layer "F.SilkS")
			(hide yes)
			(effects
				(font
					(size 1.27 1.27)
				)
			)
		)
		(property "Value" ""
			(at 0 0 270)
			(layer "F.Fab")
			(effects
				(font
					(size 1.27 1.27)
				)
			)
		)
		(duplicate_pad_numbers_are_jumpers no)
		(fp_line
			(start -0.7874 0.4064)
			(end -0.7874 -0.4064)
			(stroke
				(width 0.1524)
				(type default)
			)
			(layer "F.SilkS")
		)
		(fp_line
			(start 0.7874 0.4064)
			(end -0.7874 0.4064)
			(stroke
				(width 0.1524)
				(type default)
			)
			(layer "F.SilkS")
		)
		(fp_line
			(start -0.7874 -0.4064)
			(end 0.7874 -0.4064)
			(stroke
				(width 0.1524)
				(type default)
			)
			(layer "F.SilkS")
		)
		(fp_line
			(start 0.7874 -0.4064)
			(end 0.7874 0.4064)
			(stroke
				(width 0.1524)
				(type default)
			)
			(layer "F.SilkS")
		)
		(fp_line
			(start -0.67945 0.3048)
			(end -0.67945 -0.305054)
			(stroke
				(width 0.1)
				(type default)
			)
			(layer "F.Fab")
		)
		(fp_line
			(start -0.12065 0.3048)
			(end -0.67945 0.3048)
			(stroke
				(width 0.1)
				(type default)
			)
			(layer "F.Fab")
		)
		(fp_line
			(start 0.120396 0.3048)
			(end 0.120396 0.2794)
			(stroke
				(width 0.1)
				(type default)
			)
			(layer "F.Fab")
		)
		(fp_line
			(start 0.67945 0.3048)
			(end 0.120396 0.3048)
			(stroke
				(width 0.1)
				(type default)
			)
			(layer "F.Fab")
		)
		(fp_line
			(start -0.12065 0.2794)
			(end -0.12065 0.3048)
			(stroke
				(width 0.1)
				(type default)
			)
			(layer "F.Fab")
		)
		(fp_line
			(start 0.120396 0.2794)
			(end -0.12065 0.2794)
			(stroke
				(width 0.1)
				(type default)
			)
			(layer "F.Fab")
		)
		(fp_line
			(start -0.12065 -0.2794)
			(end 0.12065 -0.2794)
			(stroke
				(width 0.1)
				(type default)
			)
			(layer "F.Fab")
		)
		(fp_line
			(start 0.12065 -0.2794)
			(end 0.12065 -0.3048)
			(stroke
				(width 0.1)
				(type default)
			)
			(layer "F.Fab")
		)
		(fp_line
			(start 0.12065 -0.3048)
			(end 0.67945 -0.3048)
			(stroke
				(width 0.1)
				(type default)
			)
			(layer "F.Fab")
		)
		(fp_line
			(start 0.67945 -0.3048)
			(end 0.67945 0.3048)
			(stroke
				(width 0.1)
				(type default)
			)
			(layer "F.Fab")
		)
		(fp_line
			(start -0.67945 -0.305054)
			(end -0.12065 -0.305054)
			(stroke
				(width 0.1)
				(type default)
			)
			(layer "F.Fab")
		)
		(fp_line
			(start -0.12065 -0.305054)
			(end -0.12065 -0.2794)
			(stroke
				(width 0.1)
				(type default)
			)
			(layer "F.Fab")
		)
		(pad "1" smd circle
			(at -0.40005 0 270)
			(size 0 0)
			(layers "F.Cu" "F.Mask" "F.Paste")
			(net "GND")
		)
		(pad "2" smd circle
			(at 0.40005 0 270)
			(size 0 0)
			(layers "F.Cu" "F.Mask" "F.Paste")
			(net "P12V_E1S_REG_0")
		)
	)
	(footprint ""
		(layer "F.Cu")
		(at 413.928306 -133.66242)
		(property "Reference" "PC1850"
			(at 0 0 0)
			(layer "F.SilkS")
			(hide yes)
			(effects
				(font
					(size 1.27 1.27)
				)
			)
		)
		(property "Value" ""
			(at 0 0 0)
			(layer "F.Fab")
			(effects
				(font
					(size 1.27 1.27)
				)
			)
		)
		(duplicate_pad_numbers_are_jumpers no)
		(fp_line
			(start -1.524 -0.762)
			(end 1.524 -0.762)
			(stroke
				(width 0.1524)
				(type default)
			)
			(layer "F.SilkS")
		)
		(fp_line
			(start -1.524 0.762)
			(end -1.524 -0.762)
			(stroke
				(width 0.1524)
				(type default)
			)
			(layer "F.SilkS")
		)
		(fp_line
			(start 1.524 -0.762)
			(end 1.524 0.762)
			(stroke
				(width 0.1524)
				(type default)
			)
			(layer "F.SilkS")
		)
		(fp_line
			(start 1.524 0.762)
			(end -1.524 0.762)
			(stroke
				(width 0.1524)
				(type default)
			)
			(layer "F.SilkS")
		)
		(fp_line
			(start -1.1049 -0.724916)
			(end -1.1049 0.724916)
			(stroke
				(width 0.1)
				(type default)
			)
			(layer "F.Fab")
		)
		(fp_line
			(start -1.1049 0.724916)
			(end 1.1049 0.724916)
			(stroke
				(width 0.1)
				(type default)
			)
			(layer "F.Fab")
		)
		(fp_line
			(start 1.1049 -0.724916)
			(end -1.1049 -0.724916)
			(stroke
				(width 0.1)
				(type default)
			)
			(layer "F.Fab")
		)
		(fp_line
			(start 1.1049 0.724916)
			(end 1.1049 -0.724916)
			(stroke
				(width 0.1)
				(type default)
			)
			(layer "F.Fab")
		)
		(pad "1" smd rect
			(at -0.889 0 180)
			(size 1.016 1.27)
			(layers "F.Cu" "F.Mask" "F.Paste")
			(net "SW_P5V_AUX_FLT")
		)
		(pad "2" smd rect
			(at 0.889 0 180)
			(size 1.016 1.27)
			(layers "F.Cu" "F.Mask" "F.Paste")
			(net "GND")
		)
	)
	(footprint ""
		(layer "F.Cu")
		(at 403.142958 -321.002152 90)
		(property "Reference" "R449"
			(at 0 0 90)
			(layer "F.SilkS")
			(hide yes)
			(effects
				(font
					(size 1.27 1.27)
				)
			)
		)
		(property "Value" ""
			(at 0 0 90)
			(layer "F.Fab")
			(effects
				(font
					(size 1.27 1.27)
				)
			)
		)
		(duplicate_pad_numbers_are_jumpers no)
		(fp_line
			(start 0.7874 -0.4064)
			(end 0.7874 0.4064)
			(stroke
				(width 0.1524)
				(type default)
			)
			(layer "F.SilkS")
		)
		(fp_line
			(start -0.7874 -0.4064)
			(end 0.7874 -0.4064)
			(stroke
				(width 0.1524)
				(type default)
			)
			(layer "F.SilkS")
		)
		(fp_line
			(start 0.7874 0.4064)
			(end -0.7874 0.4064)
			(stroke
				(width 0.1524)
				(type default)
			)
			(layer "F.SilkS")
		)
		(fp_line
			(start -0.7874 0.4064)
			(end -0.7874 -0.4064)
			(stroke
				(width 0.1524)
				(type default)
			)
			(layer "F.SilkS")
		)
		(fp_line
			(start -0.12065 -0.305054)
			(end -0.12065 -0.2794)
			(stroke
				(width 0.1)
				(type default)
			)
			(layer "F.Fab")
		)
		(fp_line
			(start -0.67945 -0.305054)
			(end -0.12065 -0.305054)
			(stroke
				(width 0.1)
				(type default)
			)
			(layer "F.Fab")
		)
		(fp_line
			(start 0.67945 -0.3048)
			(end 0.67945 0.3048)
			(stroke
				(width 0.1)
				(type default)
			)
			(layer "F.Fab")
		)
		(fp_line
			(start 0.12065 -0.3048)
			(end 0.67945 -0.3048)
			(stroke
				(width 0.1)
				(type default)
			)
			(layer "F.Fab")
		)
		(fp_line
			(start 0.12065 -0.2794)
			(end 0.12065 -0.3048)
			(stroke
				(width 0.1)
				(type default)
			)
			(layer "F.Fab")
		)
		(fp_line
			(start -0.12065 -0.2794)
			(end 0.12065 -0.2794)
			(stroke
				(width 0.1)
				(type default)
			)
			(layer "F.Fab")
		)
		(fp_line
			(start 0.120396 0.2794)
			(end -0.12065 0.2794)
			(stroke
				(width 0.1)
				(type default)
			)
			(layer "F.Fab")
		)
		(fp_line
			(start -0.12065 0.2794)
			(end -0.12065 0.3048)
			(stroke
				(width 0.1)
				(type default)
			)
			(layer "F.Fab")
		)
		(fp_line
			(start 0.67945 0.3048)
			(end 0.120396 0.3048)
			(stroke
				(width 0.1)
				(type default)
			)
			(layer "F.Fab")
		)
		(fp_line
			(start 0.120396 0.3048)
			(end 0.120396 0.2794)
			(stroke
				(width 0.1)
				(type default)
			)
			(layer "F.Fab")
		)
		(fp_line
			(start -0.12065 0.3048)
			(end -0.67945 0.3048)
			(stroke
				(width 0.1)
				(type default)
			)
			(layer "F.Fab")
		)
		(fp_line
			(start -0.67945 0.3048)
			(end -0.67945 -0.305054)
			(stroke
				(width 0.1)
				(type default)
			)
			(layer "F.Fab")
		)
		(pad "1" smd circle
			(at -0.40005 0 90)
			(size 0 0)
			(layers "F.Cu" "F.Mask" "F.Paste")
			(net "CPU0_SLP_S3_N")
		)
		(pad "2" smd circle
			(at 0.40005 0 90)
			(size 0 0)
			(layers "F.Cu" "F.Mask" "F.Paste")
			(net "PVDD18_S5_P0")
		)
	)
)
